(kicad_pcb
	(version 20260206)
	(generator "pcbnew")
	(generator_version "10.0")
	(general
		(thickness 1.6)
		(legacy_teardrops no)
	)
	(paper "A4")
	(title_block
		(title "Wiwynn_Tioga_Pass_MB.brd")
		(comment 1 "Tioga Pass / footprints 1418-1424 of 4770")
	)
	(layers
		(0 "F.Cu" signal "TOP")
		(4 "In1.Cu" signal "L2GND")
		(6 "In2.Cu" signal "L3")
		(8 "In3.Cu" signal "L4GND")
		(10 "In4.Cu" signal "L5")
		(12 "In5.Cu" signal "L6GND")
		(14 "In6.Cu" signal "L7VCC")
		(16 "In7.Cu" signal "L8VCC")
		(18 "In8.Cu" signal "L9GND")
		(20 "In9.Cu" signal "L10")
		(22 "In10.Cu" signal "L11GND")
		(24 "In11.Cu" signal "L12")
		(26 "In12.Cu" signal "L13GND")
		(2 "B.Cu" signal "BOTTOM")
		(9 "F.Adhes" user "F.Adhesive")
		(11 "B.Adhes" user "B.Adhesive")
		(13 "F.Paste" user "Package Geometry/Pastemask Top")
		(15 "B.Paste" user "Package Geometry/Pastemask Bottom")
		(5 "F.SilkS" user "Ref Des/Silkscreen Top")
		(7 "B.SilkS" user "Ref Des/Silkscreen Bottom")
		(1 "F.Mask" user "Board Geometry/Soldermask Top")
		(3 "B.Mask" user "Board Geometry/Soldermask Bottom")
		(17 "Dwgs.User" user "User.Drawings")
		(19 "Cmts.User" user "User.Comments")
		(21 "Eco1.User" user "User.Eco1")
		(23 "Eco2.User" user "User.Eco2")
		(25 "Edge.Cuts" user "Board Geometry/Outline")
		(27 "Margin" user)
		(31 "F.CrtYd" user "Package Geometry/Place Bound Top")
		(29 "B.CrtYd" user "Package Geometry/Place Bound Bottom")
		(35 "F.Fab" user "Ref Des/Assembly Top")
		(33 "B.Fab" user "Ref Des/Assembly Bottom")
	)
	(footprint ""
		(layer "F.Cu")
		(at 437.6293 -21.9964 -90)
		(property "Reference" "R1U1"
			(at 0 0 270)
			(layer "F.SilkS")
			(hide yes)
			(effects
				(font
					(size 1.27 1.27)
				)
			)
		)
		(property "Value" ""
			(at 0 0 270)
			(layer "F.Fab")
			(effects
				(font
					(size 1.27 1.27)
				)
			)
		)
		(duplicate_pad_numbers_are_jumpers no)
		(fp_poly
			(pts
				(xy -0.2794 -0.1016) (xy 0.2794 -0.1016) (xy 0.2794 0.9906) (xy -0.2794 0.9906)
			)
			(stroke
				(width 0)
				(type default)
			)
			(fill no)
			(layer "F.CrtYd")
		)
		(fp_line
			(start -0.2794 0.9906)
			(end 0.2794 0.9906)
			(stroke
				(width 0.1)
				(type default)
			)
			(layer "F.Fab")
		)
		(fp_line
			(start 0.2794 0.9906)
			(end 0.2794 -0.1016)
			(stroke
				(width 0.1)
				(type default)
			)
			(layer "F.Fab")
		)
		(fp_line
			(start -0.2794 -0.1016)
			(end -0.2794 0.9906)
			(stroke
				(width 0.1)
				(type default)
			)
			(layer "F.Fab")
		)
		(fp_line
			(start 0.2794 -0.1016)
			(end -0.2794 -0.1016)
			(stroke
				(width 0.1)
				(type default)
			)
			(layer "F.Fab")
		)
		(pad "1" smd rect
			(at 0 0 270)
			(size 0.508 0.508)
			(layers "F.Cu" "F.Mask" "F.Paste")
			(net "FAN_TACH3")
		)
		(pad "2" smd rect
			(at 0 0.889 270)
			(size 0.508 0.508)
			(layers "F.Cu" "F.Mask" "F.Paste")
			(net "GND")
		)
		(zone
			(layer "F.Cu")
			(hatch none 0.5)
			(connect_pads
				(clearance 0)
			)
			(min_thickness 0.25)
			(keepout
				(tracks not_allowed)
				(vias allowed)
				(pads allowed)
				(copperpour not_allowed)
				(footprints allowed)
			)
			(placement
				(enabled no)
				(sheetname "")
			)
			(fill
				(thermal_gap 0.5)
				(thermal_bridge_width 0.5)
				(island_removal_mode 0)
			)
			(polygon
				(pts
					(xy 436.9943 -22.2504) (xy 436.9943 -21.7424) (xy 437.3753 -21.7424) (xy 437.3753 -22.2504)
				)
			)
		)
		(zone
			(layer "F.Cu")
			(hatch none 0.5)
			(connect_pads
				(clearance 0)
			)
			(min_thickness 0.25)
			(keepout
				(tracks allowed)
				(vias not_allowed)
				(pads allowed)
				(copperpour not_allowed)
				(footprints allowed)
			)
			(placement
				(enabled no)
				(sheetname "")
			)
			(fill
				(thermal_gap 0.5)
				(thermal_bridge_width 0.5)
				(island_removal_mode 0)
			)
			(polygon
				(pts
					(xy 437.3753 -22.2504) (xy 437.3753 -21.7424) (xy 436.9943 -21.7424) (xy 436.9943 -22.2504)
				)
			)
		)
	)
	(footprint ""
		(layer "F.Cu")
		(at 180.8734 -131.7625)
		(property "Reference" "R4B7"
			(at 0 0 0)
			(layer "F.SilkS")
			(hide yes)
			(effects
				(font
					(size 1.27 1.27)
				)
			)
		)
		(property "Value" ""
			(at 0 0 0)
			(layer "F.Fab")
			(effects
				(font
					(size 1.27 1.27)
				)
			)
		)
		(duplicate_pad_numbers_are_jumpers no)
		(fp_poly
			(pts
				(xy -0.2794 -0.1016) (xy 0.2794 -0.1016) (xy 0.2794 0.9906) (xy -0.2794 0.9906)
			)
			(stroke
				(width 0)
				(type default)
			)
			(fill no)
			(layer "F.CrtYd")
		)
		(fp_line
			(start -0.2794 -0.1016)
			(end -0.2794 0.9906)
			(stroke
				(width 0.1)
				(type default)
			)
			(layer "F.Fab")
		)
		(fp_line
			(start -0.2794 0.9906)
			(end 0.2794 0.9906)
			(stroke
				(width 0.1)
				(type default)
			)
			(layer "F.Fab")
		)
		(fp_line
			(start 0.2794 -0.1016)
			(end -0.2794 -0.1016)
			(stroke
				(width 0.1)
				(type default)
			)
			(layer "F.Fab")
		)
		(fp_line
			(start 0.2794 0.9906)
			(end 0.2794 -0.1016)
			(stroke
				(width 0.1)
				(type default)
			)
			(layer "F.Fab")
		)
		(pad "1" smd rect
			(at 0 0)
			(size 0.508 0.508)
			(layers "F.Cu" "F.Mask" "F.Paste")
			(net "PWRGD_PVPP_KLM_R")
		)
		(pad "2" smd rect
			(at 0 0.889)
			(size 0.508 0.508)
			(layers "F.Cu" "F.Mask" "F.Paste")
			(net "PWRGD_PVPP_KLM")
		)
		(zone
			(layer "F.Cu")
			(hatch none 0.5)
			(connect_pads
				(clearance 0)
			)
			(min_thickness 0.25)
			(keepout
				(tracks allowed)
				(vias not_allowed)
				(pads allowed)
				(copperpour not_allowed)
				(footprints allowed)
			)
			(placement
				(enabled no)
				(sheetname "")
			)
			(fill
				(thermal_gap 0.5)
				(thermal_bridge_width 0.5)
				(island_removal_mode 0)
			)
			(polygon
				(pts
					(xy 180.6194 -131.5085) (xy 181.1274 -131.5085) (xy 181.1274 -131.1275) (xy 180.6194 -131.1275)
				)
			)
		)
		(zone
			(layer "F.Cu")
			(hatch none 0.5)
			(connect_pads
				(clearance 0)
			)
			(min_thickness 0.25)
			(keepout
				(tracks not_allowed)
				(vias allowed)
				(pads allowed)
				(copperpour not_allowed)
				(footprints allowed)
			)
			(placement
				(enabled no)
				(sheetname "")
			)
			(fill
				(thermal_gap 0.5)
				(thermal_bridge_width 0.5)
				(island_removal_mode 0)
			)
			(polygon
				(pts
					(xy 180.6194 -131.1275) (xy 181.1274 -131.1275) (xy 181.1274 -131.5085) (xy 180.6194 -131.5085)
				)
			)
		)
	)
	(footprint ""
		(layer "F.Cu")
		(at 408.051 -103.8225)
		(property "Reference" "R2N6"
			(at 0 0 0)
			(layer "F.SilkS")
			(hide yes)
			(effects
				(font
					(size 1.27 1.27)
				)
			)
		)
		(property "Value" ""
			(at 0 0 0)
			(layer "F.Fab")
			(effects
				(font
					(size 1.27 1.27)
				)
			)
		)
		(duplicate_pad_numbers_are_jumpers no)
		(fp_poly
			(pts
				(xy -0.2794 -0.1016) (xy 0.2794 -0.1016) (xy 0.2794 0.9906) (xy -0.2794 0.9906)
			)
			(stroke
				(width 0)
				(type default)
			)
			(fill no)
			(layer "F.CrtYd")
		)
		(fp_line
			(start -0.2794 -0.1016)
			(end -0.2794 0.9906)
			(stroke
				(width 0.1)
				(type default)
			)
			(layer "F.Fab")
		)
		(fp_line
			(start -0.2794 0.9906)
			(end 0.2794 0.9906)
			(stroke
				(width 0.1)
				(type default)
			)
			(layer "F.Fab")
		)
		(fp_line
			(start 0.2794 -0.1016)
			(end -0.2794 -0.1016)
			(stroke
				(width 0.1)
				(type default)
			)
			(layer "F.Fab")
		)
		(fp_line
			(start 0.2794 0.9906)
			(end 0.2794 -0.1016)
			(stroke
				(width 0.1)
				(type default)
			)
			(layer "F.Fab")
		)
		(pad "1" smd rect
			(at 0 0)
			(size 0.508 0.508)
			(layers "F.Cu" "F.Mask" "F.Paste")
			(net "P3V3_STBY")
		)
		(pad "2" smd rect
			(at 0 0.889)
			(size 0.508 0.508)
			(layers "F.Cu" "F.Mask" "F.Paste")
			(net "FM_GBE_LOM_DISABLE_N")
		)
		(zone
			(layer "F.Cu")
			(hatch none 0.5)
			(connect_pads
				(clearance 0)
			)
			(min_thickness 0.25)
			(keepout
				(tracks allowed)
				(vias not_allowed)
				(pads allowed)
				(copperpour not_allowed)
				(footprints allowed)
			)
			(placement
				(enabled no)
				(sheetname "")
			)
			(fill
				(thermal_gap 0.5)
				(thermal_bridge_width 0.5)
				(island_removal_mode 0)
			)
			(polygon
				(pts
					(xy 407.797 -103.5685) (xy 408.305 -103.5685) (xy 408.305 -103.1875) (xy 407.797 -103.1875)
				)
			)
		)
		(zone
			(layer "F.Cu")
			(hatch none 0.5)
			(connect_pads
				(clearance 0)
			)
			(min_thickness 0.25)
			(keepout
				(tracks not_allowed)
				(vias allowed)
				(pads allowed)
				(copperpour not_allowed)
				(footprints allowed)
			)
			(placement
				(enabled no)
				(sheetname "")
			)
			(fill
				(thermal_gap 0.5)
				(thermal_bridge_width 0.5)
				(island_removal_mode 0)
			)
			(polygon
				(pts
					(xy 407.797 -103.1875) (xy 408.305 -103.1875) (xy 408.305 -103.5685) (xy 407.797 -103.5685)
				)
			)
		)
	)
	(footprint ""
		(layer "F.Cu")
		(at 394.8176 -64.8462 180)
		(property "Reference" "C8E13"
			(at 0 0 180)
			(layer "F.SilkS")
			(hide yes)
			(effects
				(font
					(size 1.27 1.27)
				)
			)
		)
		(property "Value" ""
			(at 0 0 180)
			(layer "F.Fab")
			(effects
				(font
					(size 1.27 1.27)
				)
			)
		)
		(duplicate_pad_numbers_are_jumpers no)
		(fp_poly
			(pts
				(xy 0.3048 -0.1016) (xy 0.3048 0.9906) (xy -0.3048 0.9906) (xy -0.3048 -0.1016)
			)
			(stroke
				(width 0)
				(type default)
			)
			(fill no)
			(layer "F.CrtYd")
		)
		(fp_line
			(start 0.3048 0.9906)
			(end 0.3048 -0.1016)
			(stroke
				(width 0.1)
				(type default)
			)
			(layer "F.Fab")
		)
		(fp_line
			(start 0.3048 -0.1016)
			(end -0.3048 -0.1016)
			(stroke
				(width 0.1)
				(type default)
			)
			(layer "F.Fab")
		)
		(fp_line
			(start -0.3048 0.9906)
			(end 0.3048 0.9906)
			(stroke
				(width 0.1)
				(type default)
			)
			(layer "F.Fab")
		)
		(fp_line
			(start -0.3048 -0.1016)
			(end -0.3048 0.9906)
			(stroke
				(width 0.1)
				(type default)
			)
			(layer "F.Fab")
		)
		(pad "1" smd rect
			(at 0 0 180)
			(size 0.508 0.508)
			(layers "F.Cu" "F.Mask" "F.Paste")
			(net "PWRGD_P12V_HSC_DLY")
		)
		(pad "2" smd rect
			(at 0 0.889 180)
			(size 0.508 0.508)
			(layers "F.Cu" "F.Mask" "F.Paste")
			(net "AGND_P5V_STBY")
		)
		(zone
			(layer "F.Cu")
			(hatch none 0.5)
			(connect_pads
				(clearance 0)
			)
			(min_thickness 0.25)
			(keepout
				(tracks not_allowed)
				(vias allowed)
				(pads allowed)
				(copperpour not_allowed)
				(footprints allowed)
			)
			(placement
				(enabled no)
				(sheetname "")
			)
			(fill
				(thermal_gap 0.5)
				(thermal_bridge_width 0.5)
				(island_removal_mode 0)
			)
			(polygon
				(pts
					(xy 395.0716 -65.4812) (xy 394.5636 -65.4812) (xy 394.5636 -65.1002) (xy 395.0716 -65.1002)
				)
			)
		)
		(zone
			(layer "F.Cu")
			(hatch none 0.5)
			(connect_pads
				(clearance 0)
			)
			(min_thickness 0.25)
			(keepout
				(tracks allowed)
				(vias not_allowed)
				(pads allowed)
				(copperpour not_allowed)
				(footprints allowed)
			)
			(placement
				(enabled no)
				(sheetname "")
			)
			(fill
				(thermal_gap 0.5)
				(thermal_bridge_width 0.5)
				(island_removal_mode 0)
			)
			(polygon
				(pts
					(xy 395.0716 -65.1002) (xy 394.5636 -65.1002) (xy 394.5636 -65.4812) (xy 395.0716 -65.4812)
				)
			)
		)
	)
	(footprint ""
		(layer "F.Cu")
		(at 341.376 -19.558 180)
		(property "Reference" "C7F14"
			(at 0 0 180)
			(layer "F.SilkS")
			(hide yes)
			(effects
				(font
					(size 1.27 1.27)
				)
			)
		)
		(property "Value" ""
			(at 0 0 180)
			(layer "F.Fab")
			(effects
				(font
					(size 1.27 1.27)
				)
			)
		)
		(duplicate_pad_numbers_are_jumpers no)
		(fp_poly
			(pts
				(xy 0.3048 -0.1016) (xy 0.3048 0.9906) (xy -0.3048 0.9906) (xy -0.3048 -0.1016)
			)
			(stroke
				(width 0)
				(type default)
			)
			(fill no)
			(layer "F.CrtYd")
		)
		(fp_line
			(start 0.3048 0.9906)
			(end 0.3048 -0.1016)
			(stroke
				(width 0.1)
				(type default)
			)
			(layer "F.Fab")
		)
		(fp_line
			(start 0.3048 -0.1016)
			(end -0.3048 -0.1016)
			(stroke
				(width 0.1)
				(type default)
			)
			(layer "F.Fab")
		)
		(fp_line
			(start -0.3048 0.9906)
			(end 0.3048 0.9906)
			(stroke
				(width 0.1)
				(type default)
			)
			(layer "F.Fab")
		)
		(fp_line
			(start -0.3048 -0.1016)
			(end -0.3048 0.9906)
			(stroke
				(width 0.1)
				(type default)
			)
			(layer "F.Fab")
		)
		(pad "1" smd rect
			(at 0 0 180)
			(size 0.508 0.508)
			(layers "F.Cu" "F.Mask" "F.Paste")
			(net "PWRGD_PVDDQ_ABC_R")
		)
		(pad "2" smd rect
			(at 0 0.889 180)
			(size 0.508 0.508)
			(layers "F.Cu" "F.Mask" "F.Paste")
			(net "GND")
		)
		(zone
			(layer "F.Cu")
			(hatch none 0.5)
			(connect_pads
				(clearance 0)
			)
			(min_thickness 0.25)
			(keepout
				(tracks not_allowed)
				(vias allowed)
				(pads allowed)
				(copperpour not_allowed)
				(footprints allowed)
			)
			(placement
				(enabled no)
				(sheetname "")
			)
			(fill
				(thermal_gap 0.5)
				(thermal_bridge_width 0.5)
				(island_removal_mode 0)
			)
			(polygon
				(pts
					(xy 341.63 -20.193) (xy 341.122 -20.193) (xy 341.122 -19.812) (xy 341.63 -19.812)
				)
			)
		)
		(zone
			(layer "F.Cu")
			(hatch none 0.5)
			(connect_pads
				(clearance 0)
			)
			(min_thickness 0.25)
			(keepout
				(tracks allowed)
				(vias not_allowed)
				(pads allowed)
				(copperpour not_allowed)
				(footprints allowed)
			)
			(placement
				(enabled no)
				(sheetname "")
			)
			(fill
				(thermal_gap 0.5)
				(thermal_bridge_width 0.5)
				(island_removal_mode 0)
			)
			(polygon
				(pts
					(xy 341.63 -19.812) (xy 341.122 -19.812) (xy 341.122 -20.193) (xy 341.63 -20.193)
				)
			)
		)
	)
	(footprint ""
		(layer "F.Cu")
		(at 101.3968 -12.954 90)
		(property "Reference" "C2G5"
			(at 1.848866 0.752348 90)
			(unlocked yes)
			(layer "F.SilkS")
			(effects
				(font
					(size 1.27 0.9652)
					(thickness 0.1524)
				)
			)
		)
		(property "Value" ""
			(at 0 0 90)
			(layer "F.Fab")
			(effects
				(font
					(size 1.27 1.27)
				)
			)
		)
		(duplicate_pad_numbers_are_jumpers no)
		(fp_rect
			(start -0.500126 1.598422)
			(end 0.500126 -0.201422)
			(stroke
				(width 0)
				(type default)
			)
			(fill no)
			(layer "F.CrtYd")
		)
		(fp_line
			(start 0.500126 -0.201422)
			(end 0.500126 1.598422)
			(stroke
				(width 0.1)
				(type default)
			)
			(layer "F.Fab")
		)
		(fp_line
			(start -0.500126 -0.201422)
			(end 0.500126 -0.201422)
			(stroke
				(width 0.1)
				(type default)
			)
			(layer "F.Fab")
		)
		(fp_line
			(start 0.500126 1.598422)
			(end -0.500126 1.598422)
			(stroke
				(width 0.1)
				(type default)
			)
			(layer "F.Fab")
		)
		(fp_line
			(start -0.500126 1.598422)
			(end -0.500126 -0.201422)
			(stroke
				(width 0.1)
				(type default)
			)
			(layer "F.Fab")
		)
		(pad "1" smd rect
			(at 0 0)
			(size 0.889 0.9906)
			(layers "F.Cu" "F.Mask" "F.Paste")
			(net "PVDDQ_GHJ")
		)
		(pad "2" smd rect
			(at 0 1.397)
			(size 0.889 0.9906)
			(layers "F.Cu" "F.Mask" "F.Paste")
			(net "GND")
		)
		(zone
			(layer "F.Cu")
			(hatch none 0.5)
			(connect_pads
				(clearance 0)
			)
			(min_thickness 0.25)
			(keepout
				(tracks allowed)
				(vias not_allowed)
				(pads allowed)
				(copperpour not_allowed)
				(footprints allowed)
			)
			(placement
				(enabled no)
				(sheetname "")
			)
			(fill
				(thermal_gap 0.5)
				(thermal_bridge_width 0.5)
				(island_removal_mode 0)
			)
			(polygon
				(pts
					(xy 102.3493 -12.4587) (xy 102.3493 -13.4493) (xy 101.8413 -13.4493) (xy 101.8413 -12.4587)
				)
			)
		)
		(zone
			(layer "F.Cu")
			(hatch none 0.5)
			(connect_pads
				(clearance 0)
			)
			(min_thickness 0.25)
			(keepout
				(tracks not_allowed)
				(vias allowed)
				(pads allowed)
				(copperpour not_allowed)
				(footprints allowed)
			)
			(placement
				(enabled no)
				(sheetname "")
			)
			(fill
				(thermal_gap 0.5)
				(thermal_bridge_width 0.5)
				(island_removal_mode 0)
			)
			(polygon
				(pts
					(xy 102.3493 -12.4587) (xy 102.3493 -13.4493) (xy 101.8413 -13.4493) (xy 101.8413 -12.4587)
				)
			)
		)
	)
	(footprint ""
		(layer "F.Cu")
		(at 395.579092 -10.968736)
		(property "Reference" "C7G23"
			(at 0 0 0)
			(layer "F.SilkS")
			(hide yes)
			(effects
				(font
					(size 1.27 1.27)
				)
			)
		)
		(property "Value" ""
			(at 0 0 0)
			(layer "F.Fab")
			(effects
				(font
					(size 1.27 1.27)
				)
			)
		)
		(duplicate_pad_numbers_are_jumpers no)
		(fp_rect
			(start -0.3048 0.9906)
			(end 0.3048 -0.1016)
			(stroke
				(width 0)
				(type default)
			)
			(fill no)
			(layer "F.CrtYd")
		)
		(fp_line
			(start -0.3048 -0.1016)
			(end -0.3048 0.9906)
			(stroke
				(width 0.1)
				(type default)
			)
			(layer "F.Fab")
		)
		(fp_line
			(start -0.3048 0.9906)
			(end 0.3048 0.9906)
			(stroke
				(width 0.1)
				(type default)
			)
			(layer "F.Fab")
		)
		(fp_line
			(start 0.3048 -0.1016)
			(end -0.3048 -0.1016)
			(stroke
				(width 0.1)
				(type default)
			)
			(layer "F.Fab")
		)
		(fp_line
			(start 0.3048 0.9906)
			(end 0.3048 -0.1016)
			(stroke
				(width 0.1)
				(type default)
			)
			(layer "F.Fab")
		)
		(pad "1" smd rect
			(at 0 0)
			(size 0.508 0.508)
			(layers "F.Cu" "F.Mask" "F.Paste")
			(net "P3E_CPU0_PE2_SS_TXP<6>")
		)
		(pad "2" smd rect
			(at 0 0.889)
			(size 0.508 0.508)
			(layers "F.Cu" "F.Mask" "F.Paste")
			(net "P3E_CPU0_PE2_SS_C_TXP<6>")
		)
		(zone
			(layer "F.Cu")
			(hatch none 0.5)
			(connect_pads
				(clearance 0)
			)
			(min_thickness 0.25)
			(keepout
				(tracks allowed)
				(vias not_allowed)
				(pads allowed)
				(copperpour not_allowed)
				(footprints allowed)
			)
			(placement
				(enabled no)
				(sheetname "")
			)
			(fill
				(thermal_gap 0.5)
				(thermal_bridge_width 0.5)
				(island_removal_mode 0)
			)
			(polygon
				(pts
					(xy 395.325092 -10.333736) (xy 395.833092 -10.333736) (xy 395.833092 -10.714736) (xy 395.325092 -10.714736)
				)
			)
		)
		(zone
			(layer "F.Cu")
			(hatch none 0.5)
			(connect_pads
				(clearance 0)
			)
			(min_thickness 0.25)
			(keepout
				(tracks not_allowed)
				(vias allowed)
				(pads allowed)
				(copperpour not_allowed)
				(footprints allowed)
			)
			(placement
				(enabled no)
				(sheetname "")
			)
			(fill
				(thermal_gap 0.5)
				(thermal_bridge_width 0.5)
				(island_removal_mode 0)
			)
			(polygon
				(pts
					(xy 395.325092 -10.333736) (xy 395.833092 -10.333736) (xy 395.833092 -10.714736) (xy 395.325092 -10.714736)
				)
			)
		)
	)
)
